# T6G (Grand Teton) — schematic netlist excerpt (pin names and nets, part order shuffled) for the footprints in the layout excerpt that follows; sources: Cadence DE-HDL packaged netlist, KiCad conversion of 04192023_DAF0TMB3IC0_F0TG_MB_C_brd_V02_OCP.brd

PR506  Q_RES  1.5 1% EMPTY  pkg 0402LF  page 201 : A = SW_PVDDCR_CPU1_P0_SW1_RC ; B = GND
R4144  Q_RES  33.2 1% CHIP  pkg 0402LF  page 81 : A = GPU_3V3IO_RSVD1_FFU_ISO_R ; B = GPU_3V3IO_RSVD1_FFU_ISO

(kicad_pcb
	(version 20260206)
	(generator "pcbnew")
	(generator_version "10.0")
	(general
		(thickness 1.6)
		(legacy_teardrops no)
	)
	(paper "A4")
	(title_block
		(title "04192023_DAF0TMB3IC0_F0TG_MB_C_brd_V02_OCP.brd")
		(comment 1 "Grand Teton / footprints 68-69 of 8354")
	)
	(layers
		(0 "F.Cu" signal "TOP")
		(4 "In1.Cu" signal "GND")
		(6 "In2.Cu" signal "IN1")
		(8 "In3.Cu" signal "GND1")
		(10 "In4.Cu" signal "IN2")
		(12 "In5.Cu" signal "GND2")
		(14 "In6.Cu" signal "IN3")
		(16 "In7.Cu" signal "GND3")
		(18 "In8.Cu" signal "VCC")
		(20 "In9.Cu" signal "VCC1")
		(22 "In10.Cu" signal "GND4")
		(24 "In11.Cu" signal "IN4")
		(26 "In12.Cu" signal "GND5")
		(28 "In13.Cu" signal "IN5")
		(30 "In14.Cu" signal "GND6")
		(32 "In15.Cu" signal "IN6")
		(34 "In16.Cu" signal "GND7")
		(2 "B.Cu" signal "BOTTOM")
		(9 "F.Adhes" user "F.Adhesive")
		(11 "B.Adhes" user "B.Adhesive")
		(13 "F.Paste" user "Package Geometry/Pastemask Top")
		(15 "B.Paste" user "Package Geometry/Pastemask Bottom")
		(5 "F.SilkS" user "Ref Des/Silkscreen Top")
		(7 "B.SilkS" user "Ref Des/Silkscreen Bottom")
		(1 "F.Mask" user "Board Geometry/Soldermask Top")
		(3 "B.Mask" user "Board Geometry/Soldermask Bottom")
		(17 "Dwgs.User" user "User.Drawings")
		(19 "Cmts.User" user "User.Comments")
		(21 "Eco1.User" user "User.Eco1")
		(23 "Eco2.User" user "User.Eco2")
		(25 "Edge.Cuts" user "Board Geometry/Outline")
		(27 "Margin" user)
		(31 "F.CrtYd" user "Package Geometry/Place Bound Top")
		(29 "B.CrtYd" user "Package Geometry/Place Bound Bottom")
		(35 "F.Fab" user "Ref Des/Assembly Top")
		(33 "B.Fab" user "Ref Des/Assembly Bottom")
	)
	(footprint ""
		(layer "F.Cu")
		(at 205.243684 -120.944386)
		(property "Reference" "R4144"
			(at 0 0 0)
			(layer "F.SilkS")
			(hide yes)
			(effects
				(font
					(size 1.27 1.27)
				)
			)
		)
		(property "Value" ""
			(at 0 0 0)
			(layer "F.Fab")
			(effects
				(font
					(size 1.27 1.27)
				)
			)
		)
		(duplicate_pad_numbers_are_jumpers no)
		(fp_line
			(start -0.7874 -0.4064)
			(end 0.7874 -0.4064)
			(stroke
				(width 0.1524)
				(type default)
			)
			(layer "F.SilkS")
		)
		(fp_line
			(start -0.7874 0.4064)
			(end -0.7874 -0.4064)
			(stroke
				(width 0.1524)
				(type default)
			)
			(layer "F.SilkS")
		)
		(fp_line
			(start 0.7874 -0.4064)
			(end 0.7874 0.4064)
			(stroke
				(width 0.1524)
				(type default)
			)
			(layer "F.SilkS")
		)
		(fp_line
			(start 0.7874 0.4064)
			(end -0.7874 0.4064)
			(stroke
				(width 0.1524)
				(type default)
			)
			(layer "F.SilkS")
		)
		(fp_line
			(start -0.67945 -0.305054)
			(end -0.12065 -0.305054)
			(stroke
				(width 0.1)
				(type default)
			)
			(layer "F.Fab")
		)
		(fp_line
			(start -0.67945 0.3048)
			(end -0.67945 -0.305054)
			(stroke
				(width 0.1)
				(type default)
			)
			(layer "F.Fab")
		)
		(fp_line
			(start -0.12065 -0.305054)
			(end -0.12065 -0.2794)
			(stroke
				(width 0.1)
				(type default)
			)
			(layer "F.Fab")
		)
		(fp_line
			(start -0.12065 -0.2794)
			(end 0.12065 -0.2794)
			(stroke
				(width 0.1)
				(type default)
			)
			(layer "F.Fab")
		)
		(fp_line
			(start -0.12065 0.2794)
			(end -0.12065 0.3048)
			(stroke
				(width 0.1)
				(type default)
			)
			(layer "F.Fab")
		)
		(fp_line
			(start -0.12065 0.3048)
			(end -0.67945 0.3048)
			(stroke
				(width 0.1)
				(type default)
			)
			(layer "F.Fab")
		)
		(fp_line
			(start 0.120396 0.2794)
			(end -0.12065 0.2794)
			(stroke
				(width 0.1)
				(type default)
			)
			(layer "F.Fab")
		)
		(fp_line
			(start 0.120396 0.3048)
			(end 0.120396 0.2794)
			(stroke
				(width 0.1)
				(type default)
			)
			(layer "F.Fab")
		)
		(fp_line
			(start 0.12065 -0.3048)
			(end 0.67945 -0.3048)
			(stroke
				(width 0.1)
				(type default)
			)
			(layer "F.Fab")
		)
		(fp_line
			(start 0.12065 -0.2794)
			(end 0.12065 -0.3048)
			(stroke
				(width 0.1)
				(type default)
			)
			(layer "F.Fab")
		)
		(fp_line
			(start 0.67945 -0.3048)
			(end 0.67945 0.3048)
			(stroke
				(width 0.1)
				(type default)
			)
			(layer "F.Fab")
		)
		(fp_line
			(start 0.67945 0.3048)
			(end 0.120396 0.3048)
			(stroke
				(width 0.1)
				(type default)
			)
			(layer "F.Fab")
		)
		(pad "1" smd circle
			(at -0.40005 0)
			(size 0 0)
			(layers "F.Cu" "F.Mask" "F.Paste")
			(net "GPU_3V3IO_RSVD1_FFU_ISO_R")
		)
		(pad "2" smd circle
			(at 0.40005 0)
			(size 0 0)
			(layers "F.Cu" "F.Mask" "F.Paste")
			(net "GPU_3V3IO_RSVD1_FFU_ISO")
		)
	)
	(footprint ""
		(layer "F.Cu")
		(at 331.381862 -333.239364 90)
		(property "Reference" "PR506"
			(at 0 0 90)
			(layer "F.SilkS")
			(hide yes)
			(effects
				(font
					(size 1.27 1.27)
				)
			)
		)
		(property "Value" ""
			(at 0 0 90)
			(layer "F.Fab")
			(effects
				(font
					(size 1.27 1.27)
				)
			)
		)
		(duplicate_pad_numbers_are_jumpers no)
		(fp_line
			(start 0.7874 -0.4064)
			(end 0.7874 0.4064)
			(stroke
				(width 0.1524)
				(type default)
			)
			(layer "F.SilkS")
		)
		(fp_line
			(start -0.7874 -0.4064)
			(end 0.7874 -0.4064)
			(stroke
				(width 0.1524)
				(type default)
			)
			(layer "F.SilkS")
		)
		(fp_line
			(start 0.7874 0.4064)
			(end -0.7874 0.4064)
			(stroke
				(width 0.1524)
				(type default)
			)
			(layer "F.SilkS")
		)
		(fp_line
			(start -0.7874 0.4064)
			(end -0.7874 -0.4064)
			(stroke
				(width 0.1524)
				(type default)
			)
			(layer "F.SilkS")
		)
		(fp_line
			(start -0.12065 -0.305054)
			(end -0.12065 -0.2794)
			(stroke
				(width 0.1)
				(type default)
			)
			(layer "F.Fab")
		)
		(fp_line
			(start -0.67945 -0.305054)
			(end -0.12065 -0.305054)
			(stroke
				(width 0.1)
				(type default)
			)
			(layer "F.Fab")
		)
		(fp_line
			(start 0.67945 -0.3048)
			(end 0.67945 0.3048)
			(stroke
				(width 0.1)
				(type default)
			)
			(layer "F.Fab")
		)
		(fp_line
			(start 0.12065 -0.3048)
			(end 0.67945 -0.3048)
			(stroke
				(width 0.1)
				(type default)
			)
			(layer "F.Fab")
		)
		(fp_line
			(start 0.12065 -0.2794)
			(end 0.12065 -0.3048)
			(stroke
				(width 0.1)
				(type default)
			)
			(layer "F.Fab")
		)
		(fp_line
			(start -0.12065 -0.2794)
			(end 0.12065 -0.2794)
			(stroke
				(width 0.1)
				(type default)
			)
			(layer "F.Fab")
		)
		(fp_line
			(start 0.120396 0.2794)
			(end -0.12065 0.2794)
			(stroke
				(width 0.1)
				(type default)
			)
			(layer "F.Fab")
		)
		(fp_line
			(start -0.12065 0.2794)
			(end -0.12065 0.3048)
			(stroke
				(width 0.1)
				(type default)
			)
			(layer "F.Fab")
		)
		(fp_line
			(start 0.67945 0.3048)
			(end 0.120396 0.3048)
			(stroke
				(width 0.1)
				(type default)
			)
			(layer "F.Fab")
		)
		(fp_line
			(start 0.120396 0.3048)
			(end 0.120396 0.2794)
			(stroke
				(width 0.1)
				(type default)
			)
			(layer "F.Fab")
		)
		(fp_line
			(start -0.12065 0.3048)
			(end -0.67945 0.3048)
			(stroke
				(width 0.1)
				(type default)
			)
			(layer "F.Fab")
		)
		(fp_line
			(start -0.67945 0.3048)
			(end -0.67945 -0.305054)
			(stroke
				(width 0.1)
				(type default)
			)
			(layer "F.Fab")
		)
		(pad "1" smd circle
			(at -0.40005 0 90)
			(size 0 0)
			(layers "F.Cu" "F.Mask" "F.Paste")
			(net "SW_PVDDCR_CPU1_P0_SW1_RC")
		)
		(pad "2" smd circle
			(at 0.40005 0 90)
			(size 0 0)
			(layers "F.Cu" "F.Mask" "F.Paste")
			(net "GND")
		)
	)
)
